FILE_TYPE = CONNECTIVITY;
{Allegro Design Entry HDL 16.6-p007 (v16-6-112F) 10/10/2012}
"PAGE_NUMBER" = 97;
0"NC";
1"PVCCIO_CPU0\g";
2"PVCCIO_CPU0\g";
3"PVCCIO_CPU1\g";
4"GND\g";
5"PVCCIO_CPU0\g";
6"H_CPU0_FAST_WAKE_N";
7"PU_CPU0_TSC_SYNC";
8"PU_CPU1_TSC_SYNC";
9"PD_CPU1_MCP01_DMON";
10"PD_CPU0_MCP01_DMON";
11"H_CPU1_FAST_WAKE_N";
%"RES"
"1","(-2000,4225)","0","mstr_discrete","I33";
;
ROOM"PROC_SIDEBAND"
CDS_LOCATION"R3D18"
$SEC"1"
CDS_SEC"1"
CDS_LIB"mstr_discrete"
BOM_COST"PROC_SIDEBAND"
WATTAGE"1/16W"
MATERIAL"CHIP"
PACK_TYPE"0402"
VALUE"0.0"
PART_NUMBER"G21497-005"
LOCATION"R3D18"
TOLERANCE"5%";
"B"
$PN"2"11;
"A"
$PN"1"6;
%"PVCCIO_CPU0"
"1","(-2700,4775)","0","mstr_symbols","I41";
;
HDL_POWER"PVCCIO_CPU0"
BODY_TYPE"PLUMBING"
CDS_LIB"mstr_symbols"
VOLTAGE"1.1V";
"G\NAC"1;
%"RES"
"2","(-2700,4525)","0","mstr_discrete","I42";
;
ROOM"PROC_SIDEBAND"
CDS_LOCATION"R4R4"
$SEC"1"
CDS_SEC"1"
CDS_LIB"mstr_discrete"
WATTAGE"1/16W"
MATERIAL"CHIP"
PACK_TYPE"0402"
TOLERANCE"1%"
VALUE"150.0"
PART_NUMBER"G21796-009"
LOCATION"R4R4";
"A"
$PN"1"1;
"B"
$PN"2"6;
%"RES"
"2","(-1200,4525)","0","mstr_discrete","I44";
;
ROOM"PROC_SIDEBAND"
CDS_LOCATION"R7P20"
$SEC"1"
CDS_SEC"1"
CDS_LIB"mstr_discrete"
WATTAGE"1/16W"
MATERIAL"CHIP"
PACK_TYPE"0402"
TOLERANCE"1%"
VALUE"150.0"
PART_NUMBER"G21796-009"
LOCATION"R7P20";
"A"
$PN"1"5;
"B"
$PN"2"11;
%"PVCCIO_CPU0"
"1","(-3100,1625)","0","mstr_symbols","I71";
;
HDL_POWER"PVCCIO_CPU0"
BODY_TYPE"PLUMBING"
CDS_LIB"mstr_symbols"
VOLTAGE"1.1V";
"G\NAC"2;
%"RES"
"1","(-2625,1425)","0","mstr_discrete","I72";
;
CDS_SEC"1"
ROOM"PROC_SIDEBAND"
CDS_LOCATION"R4P21"
SEC"1"
BOM_COST"PROC_SIDEBAND"
CDS_LIB"mstr_discrete"
SEC_TYPE"0402"
WATTAGE"1/16W"
MATERIAL"CHIP"
PACK_TYPE"0402"
TOLERANCE"1.0%"
VALUE"240"
PART_NUMBER"G21796-294"
LOCATION"R4P21";
"B"
$PN"2"7;
"A"
$PN"1"2;
%"RES"
"1","(-2600,800)","0","mstr_discrete","I76";
;
CDS_SEC"1"
ROOM"PROC_SIDEBAND"
CDS_LOCATION"R4C10"
SEC"1"
BOM_COST"PROC_SIDEBAND"
CDS_LIB"mstr_discrete"
SEC_TYPE"0402"
WATTAGE"1/16W"
MATERIAL"CHIP"
PACK_TYPE"0402"
TOLERANCE"1.0%"
VALUE"240"
PART_NUMBER"G21796-294"
LOCATION"R4C10";
"B"
$PN"2"8;
"A"
$PN"1"3;
%"PVCCIO_CPU1"
"1","(-3075,1000)","0","mstr_symbols","I78";
;
HDL_POWER"PVCCIO_CPU1"
BODY_TYPE"PLUMBING"
CDS_LIB"mstr_symbols"
VOLTAGE"1.1V";
"G\NAC"3;
%"RES"
"1","(-2375,3175)","0","mstr_discrete","I80";
;
CDS_SEC"1"
ROOM"CPU0"
CDS_LOCATION"R4P5"
SEC"1"
SEC_TYPE"0402"
CDS_LIB"mstr_discrete"
WATTAGE"1/16W"
MATERIAL"CHIP"
PACK_TYPE"0402"
TOLERANCE"1%"
VALUE"10.0K"
LOCATION"R4P5"
PART_NUMBER"G21796-016";
"B"
$PN"2"10;
"A"
$PN"1"4;
%"RES"
"1","(-2375,2825)","0","mstr_discrete","I81";
;
CDS_SEC"1"
ROOM"CPU1"
CDS_LOCATION"R7P13"
SEC"1"
SEC_TYPE"0402"
CDS_LIB"mstr_discrete"
WATTAGE"1/16W"
MATERIAL"CHIP"
PACK_TYPE"0402"
TOLERANCE"1%"
VALUE"10.0K"
PART_NUMBER"G21796-016"
LOCATION"R7P13";
"B"
$PN"2"9;
"A"
$PN"1"4;
%"GND"
"1","(-3075,2425)","0","mstr_symbols","I82";
;
HDL_POWER"GND"
BODY_TYPE"PLUMBING"
CDS_LIB"mstr_symbols"
SIZE"1B"
VOLTAGE"0.0V";
"A\NAC"4;
%"PVCCIO_CPU0"
"1","(-1200,4775)","0","mstr_symbols","I85";
;
HDL_POWER"PVCCIO_CPU0"
BODY_TYPE"PLUMBING"
CDS_LIB"mstr_symbols"
VOLTAGE"1.1V";
"G\NAC"5;
END.
